# BASEBOARD_FAB2 (Tioga Pass) — schematic netlist excerpt (pin names and nets, part order shuffled) for the footprints in the layout excerpt that follows; sources: Cadence DE-HDL packaged netlist, KiCad conversion of Wiwynn_Tioga_Pass_MB.brd

C4D36  CAP_A  1.0UF 6.3V 10% X6S  pkg 0402V  page 213 : A = VR_PVCCIO_CPU1_VDD ; B = GND
R3D12  RES  240 1.0% EMPTY  pkg 0402  page 90 : A = GND ; B = PD_CPU1_TXT_PLTEN

(kicad_pcb
	(version 20260206)
	(generator "pcbnew")
	(generator_version "10.0")
	(general
		(thickness 1.6)
		(legacy_teardrops no)
	)
	(paper "A4")
	(title_block
		(title "Wiwynn_Tioga_Pass_MB.brd")
		(comment 1 "Tioga Pass / footprints 1756-1757 of 4770")
	)
	(layers
		(0 "F.Cu" signal "TOP")
		(4 "In1.Cu" signal "L2GND")
		(6 "In2.Cu" signal "L3")
		(8 "In3.Cu" signal "L4GND")
		(10 "In4.Cu" signal "L5")
		(12 "In5.Cu" signal "L6GND")
		(14 "In6.Cu" signal "L7VCC")
		(16 "In7.Cu" signal "L8VCC")
		(18 "In8.Cu" signal "L9GND")
		(20 "In9.Cu" signal "L10")
		(22 "In10.Cu" signal "L11GND")
		(24 "In11.Cu" signal "L12")
		(26 "In12.Cu" signal "L13GND")
		(2 "B.Cu" signal "BOTTOM")
		(9 "F.Adhes" user "F.Adhesive")
		(11 "B.Adhes" user "B.Adhesive")
		(13 "F.Paste" user "Package Geometry/Pastemask Top")
		(15 "B.Paste" user "Package Geometry/Pastemask Bottom")
		(5 "F.SilkS" user "Ref Des/Silkscreen Top")
		(7 "B.SilkS" user "Ref Des/Silkscreen Bottom")
		(1 "F.Mask" user "Board Geometry/Soldermask Top")
		(3 "B.Mask" user "Board Geometry/Soldermask Bottom")
		(17 "Dwgs.User" user "User.Drawings")
		(19 "Cmts.User" user "User.Comments")
		(21 "Eco1.User" user "User.Eco1")
		(23 "Eco2.User" user "User.Eco2")
		(25 "Edge.Cuts" user "Board Geometry/Outline")
		(27 "Margin" user)
		(31 "F.CrtYd" user "Package Geometry/Place Bound Top")
		(29 "B.CrtYd" user "Package Geometry/Place Bound Bottom")
		(35 "F.Fab" user "Ref Des/Assembly Top")
		(33 "B.Fab" user "Ref Des/Assembly Bottom")
	)
	(footprint ""
		(layer "F.Cu")
		(at 173.7487 -69.723 90)
		(property "Reference" "C4D36"
			(at 0 0 90)
			(layer "F.SilkS")
			(hide yes)
			(effects
				(font
					(size 1.27 1.27)
				)
			)
		)
		(property "Value" ""
			(at 0 0 90)
			(layer "F.Fab")
			(effects
				(font
					(size 1.27 1.27)
				)
			)
		)
		(duplicate_pad_numbers_are_jumpers no)
		(fp_poly
			(pts
				(xy 0.3048 -0.1016) (xy 0.3048 0.9906) (xy -0.3048 0.9906) (xy -0.3048 -0.1016)
			)
			(stroke
				(width 0)
				(type default)
			)
			(fill no)
			(layer "F.CrtYd")
		)
		(fp_line
			(start 0.3048 -0.1016)
			(end -0.3048 -0.1016)
			(stroke
				(width 0.1)
				(type default)
			)
			(layer "F.Fab")
		)
		(fp_line
			(start -0.3048 -0.1016)
			(end -0.3048 0.9906)
			(stroke
				(width 0.1)
				(type default)
			)
			(layer "F.Fab")
		)
		(fp_line
			(start 0.3048 0.9906)
			(end 0.3048 -0.1016)
			(stroke
				(width 0.1)
				(type default)
			)
			(layer "F.Fab")
		)
		(fp_line
			(start -0.3048 0.9906)
			(end 0.3048 0.9906)
			(stroke
				(width 0.1)
				(type default)
			)
			(layer "F.Fab")
		)
		(pad "1" smd rect
			(at 0 0 90)
			(size 0.508 0.508)
			(layers "F.Cu" "F.Mask" "F.Paste")
			(net "VR_PVCCIO_CPU1_VDD")
		)
		(pad "2" smd rect
			(at 0 0.889 90)
			(size 0.508 0.508)
			(layers "F.Cu" "F.Mask" "F.Paste")
			(net "GND")
		)
		(zone
			(layer "F.Cu")
			(hatch none 0.5)
			(connect_pads
				(clearance 0)
			)
			(min_thickness 0.25)
			(keepout
				(tracks allowed)
				(vias not_allowed)
				(pads allowed)
				(copperpour not_allowed)
				(footprints allowed)
			)
			(placement
				(enabled no)
				(sheetname "")
			)
			(fill
				(thermal_gap 0.5)
				(thermal_bridge_width 0.5)
				(island_removal_mode 0)
			)
			(polygon
				(pts
					(xy 174.0027 -69.469) (xy 174.0027 -69.977) (xy 174.3837 -69.977) (xy 174.3837 -69.469)
				)
			)
		)
		(zone
			(layer "F.Cu")
			(hatch none 0.5)
			(connect_pads
				(clearance 0)
			)
			(min_thickness 0.25)
			(keepout
				(tracks not_allowed)
				(vias allowed)
				(pads allowed)
				(copperpour not_allowed)
				(footprints allowed)
			)
			(placement
				(enabled no)
				(sheetname "")
			)
			(fill
				(thermal_gap 0.5)
				(thermal_bridge_width 0.5)
				(island_removal_mode 0)
			)
			(polygon
				(pts
					(xy 174.3837 -69.469) (xy 174.3837 -69.977) (xy 174.0027 -69.977) (xy 174.0027 -69.469)
				)
			)
		)
	)
	(footprint ""
		(layer "F.Cu")
		(at 116.332 -76.327 90)
		(property "Reference" "R3D12"
			(at 0 0 90)
			(layer "F.SilkS")
			(hide yes)
			(effects
				(font
					(size 1.27 1.27)
				)
			)
		)
		(property "Value" ""
			(at 0 0 90)
			(layer "F.Fab")
			(effects
				(font
					(size 1.27 1.27)
				)
			)
		)
		(duplicate_pad_numbers_are_jumpers no)
		(fp_poly
			(pts
				(xy -0.2794 -0.1016) (xy 0.2794 -0.1016) (xy 0.2794 0.9906) (xy -0.2794 0.9906)
			)
			(stroke
				(width 0)
				(type default)
			)
			(fill no)
			(layer "F.CrtYd")
		)
		(fp_line
			(start 0.2794 -0.1016)
			(end -0.2794 -0.1016)
			(stroke
				(width 0.1)
				(type default)
			)
			(layer "F.Fab")
		)
		(fp_line
			(start -0.2794 -0.1016)
			(end -0.2794 0.9906)
			(stroke
				(width 0.1)
				(type default)
			)
			(layer "F.Fab")
		)
		(fp_line
			(start 0.2794 0.9906)
			(end 0.2794 -0.1016)
			(stroke
				(width 0.1)
				(type default)
			)
			(layer "F.Fab")
		)
		(fp_line
			(start -0.2794 0.9906)
			(end 0.2794 0.9906)
			(stroke
				(width 0.1)
				(type default)
			)
			(layer "F.Fab")
		)
		(pad "1" smd rect
			(at 0 0 90)
			(size 0.508 0.508)
			(layers "F.Cu" "F.Mask" "F.Paste")
			(net "GND")
		)
		(pad "2" smd rect
			(at 0 0.889 90)
			(size 0.508 0.508)
			(layers "F.Cu" "F.Mask" "F.Paste")
			(net "PD_CPU1_TXT_PLTEN")
		)
		(zone
			(layer "F.Cu")
			(hatch none 0.5)
			(connect_pads
				(clearance 0)
			)
			(min_thickness 0.25)
			(keepout
				(tracks allowed)
				(vias not_allowed)
				(pads allowed)
				(copperpour not_allowed)
				(footprints allowed)
			)
			(placement
				(enabled no)
				(sheetname "")
			)
			(fill
				(thermal_gap 0.5)
				(thermal_bridge_width 0.5)
				(island_removal_mode 0)
			)
			(polygon
				(pts
					(xy 116.586 -76.073) (xy 116.586 -76.581) (xy 116.967 -76.581) (xy 116.967 -76.073)
				)
			)
		)
		(zone
			(layer "F.Cu")
			(hatch none 0.5)
			(connect_pads
				(clearance 0)
			)
			(min_thickness 0.25)
			(keepout
				(tracks not_allowed)
				(vias allowed)
				(pads allowed)
				(copperpour not_allowed)
				(footprints allowed)
			)
			(placement
				(enabled no)
				(sheetname "")
			)
			(fill
				(thermal_gap 0.5)
				(thermal_bridge_width 0.5)
				(island_removal_mode 0)
			)
			(polygon
				(pts
					(xy 116.967 -76.073) (xy 116.967 -76.581) (xy 116.586 -76.581) (xy 116.586 -76.073)
				)
			)
		)
	)
)
